Testpoint Report Status for Project:16347-1

Total # of Nets  : 38

Number of nets with "No_Test" property      :   0
Number of nets with testpoints assigned >1  :   3
Number of nets with testpoints assigned =1  :   35
Number of nets with testpoints assigned =0  :   0

Percent (All nets)                              : 100.00%
Percent (All nets Excluded "No_Test" property)  : 100.00%

DRIVE_A_26_32_ACT                  2
GND                                8
P5V_A                              3

DRIVE_A_24_30_ACT                  1
DRIVE_A_24_30_FLT_LED              1
DRIVE_A_25_31_ACT                  1
DRIVE_A_25_31_FLT_LED              1
DRIVE_A_26_32_FLT_LED              1
DRIVE_A_27_33_ACT                  1
DRIVE_A_27_33_FLT_LED              1
DRIVE_A_28_34_ACT                  1
DRIVE_A_28_34_FLT_LED              1
DRIVE_A_29_35_ACT                  1
DRIVE_A_29_35_FLT_LED              1
DRV_ACT_24_30                      1
DRV_ACT_24_30_N                    1
DRV_ACT_25_31                      1
DRV_ACT_25_31_N                    1
DRV_ACT_26_32                      1
DRV_ACT_26_32_N                    1
DRV_ACT_27_33                      1
DRV_ACT_27_33_N                    1
DRV_ACT_28_34                      1
DRV_ACT_28_34_N                    1
DRV_ACT_29_35                      1
DRV_ACT_29_35_N                    1
FLT_HDD24_30                       1
FLT_HDD24_30_N                     1
FLT_HDD25_31                       1
FLT_HDD25_31_N                     1
FLT_HDD26_32                       1
FLT_HDD26_32_N                     1
FLT_HDD27_33                       1
FLT_HDD27_33_N                     1
FLT_HDD28_34                       1
FLT_HDD28_34_N                     1
FLT_HDD29_35                       1
FLT_HDD29_35_N                     1

